(kicad_pcb
	(version 20260206)
	(generator "pcbnew")
	(generator_version "10.0")
	(general
		(thickness 1.6)
		(legacy_teardrops no)
	)
	(paper "A4")
	(title_block
		(title "12092022_DA0F0TMDCD0_F0T_Management_Board_D_brd_V3_OCP.brd")
		(comment 1 "Grand Teton / footprints 125-129 of 1440")
	)
	(layers
		(0 "F.Cu" signal "TOP")
		(4 "In1.Cu" signal "GND")
		(6 "In2.Cu" signal "IN1")
		(8 "In3.Cu" signal "GND1")
		(10 "In4.Cu" signal "IN2")
		(12 "In5.Cu" signal "VCC")
		(14 "In6.Cu" signal "VCC1")
		(16 "In7.Cu" signal "IN3")
		(18 "In8.Cu" signal "GND2")
		(20 "In9.Cu" signal "IN4")
		(22 "In10.Cu" signal "GND3")
		(2 "B.Cu" signal "BOTTOM")
		(9 "F.Adhes" user "F.Adhesive")
		(11 "B.Adhes" user "B.Adhesive")
		(13 "F.Paste" user "Package Geometry/Pastemask Top")
		(15 "B.Paste" user "Package Geometry/Pastemask Bottom")
		(5 "F.SilkS" user "Ref Des/Silkscreen Top")
		(7 "B.SilkS" user "Ref Des/Silkscreen Bottom")
		(1 "F.Mask" user "Board Geometry/Soldermask Top")
		(3 "B.Mask" user "Board Geometry/Soldermask Bottom")
		(17 "Dwgs.User" user "User.Drawings")
		(19 "Cmts.User" user "User.Comments")
		(21 "Eco1.User" user "User.Eco1")
		(23 "Eco2.User" user "User.Eco2")
		(25 "Edge.Cuts" user "Board Geometry/Outline")
		(27 "Margin" user)
		(31 "F.CrtYd" user "Package Geometry/Place Bound Top")
		(29 "B.CrtYd" user "Package Geometry/Place Bound Bottom")
		(35 "F.Fab" user "Ref Des/Assembly Top")
		(33 "B.Fab" user "Ref Des/Assembly Bottom")
	)
	(footprint ""
		(layer "F.Cu")
		(at 73.533 -13.843)
		(property "Reference" "U16"
			(at 0.7874 -1.80213 0)
			(unlocked yes)
			(layer "F.SilkS")
			(effects
				(font
					(size 0.7874 0.5842)
					(thickness 0.1524)
				)
				(justify left)
			)
		)
		(property "Value" ""
			(at 0 0 0)
			(layer "F.Fab")
			(effects
				(font
					(size 1.27 1.27)
				)
			)
		)
		(duplicate_pad_numbers_are_jumpers no)
		(fp_line
			(start -1.4986 -1.100074)
			(end 1.4986 -1.100074)
			(stroke
				(width 0.1524)
				(type default)
			)
			(layer "F.SilkS")
		)
		(fp_line
			(start -1.4986 1.100074)
			(end -1.4986 -1.100074)
			(stroke
				(width 0.1524)
				(type default)
			)
			(layer "F.SilkS")
		)
		(fp_line
			(start 1.4986 -1.100074)
			(end 1.4986 1.100074)
			(stroke
				(width 0.1524)
				(type default)
			)
			(layer "F.SilkS")
		)
		(fp_line
			(start 1.4986 1.100074)
			(end -1.4986 1.100074)
			(stroke
				(width 0.1524)
				(type default)
			)
			(layer "F.SilkS")
		)
		(fp_poly
			(pts
				(xy -1.90881 -1.728724) (xy -1.28397 -1.728724) (xy -1.612138 -1.175004)
			)
			(stroke
				(width 0)
				(type default)
			)
			(fill yes)
			(layer "F.SilkS")
		)
		(fp_line
			(start -0.67437 -1.100074)
			(end 0.67437 -1.100074)
			(stroke
				(width 0.1)
				(type default)
			)
			(layer "F.Fab")
		)
		(fp_line
			(start -0.67437 1.100074)
			(end -0.67437 -1.100074)
			(stroke
				(width 0.1)
				(type default)
			)
			(layer "F.Fab")
		)
		(fp_line
			(start 0.67437 -1.100074)
			(end 0.67437 1.100074)
			(stroke
				(width 0.1)
				(type default)
			)
			(layer "F.Fab")
		)
		(fp_line
			(start 0.67437 1.100074)
			(end -0.67437 1.100074)
			(stroke
				(width 0.1)
				(type default)
			)
			(layer "F.Fab")
		)
		(fp_poly
			(pts
				(xy -2.20472 -0.338328) (xy -2.20472 -0.963168) (xy -1.651 -0.635)
			)
			(stroke
				(width 0)
				(type default)
			)
			(fill yes)
			(layer "F.Fab")
		)
		(pad "1" smd rect
			(at -0.889 -0.649986)
			(size 1.016 0.381)
			(layers "F.Cu" "F.Mask" "F.Paste")
			(net "NC_U16_P1")
		)
		(pad "2" smd rect
			(at -0.889 0)
			(size 1.016 0.381)
			(layers "F.Cu" "F.Mask" "F.Paste")
			(net "REAR_AC_PWR_BTN_N")
		)
		(pad "3" smd rect
			(at -0.889 0.649986)
			(size 1.016 0.381)
			(layers "F.Cu" "F.Mask" "F.Paste")
			(net "GND")
		)
		(pad "4" smd rect
			(at 0.889 0.649986)
			(size 1.016 0.381)
			(layers "F.Cu" "F.Mask" "F.Paste")
			(net "AC_PWR_BTN_R1_N")
		)
		(pad "5" smd rect
			(at 0.889 -0.649986)
			(size 1.016 0.381)
			(layers "F.Cu" "F.Mask" "F.Paste")
			(net "P3V3_AUX")
		)
	)
	(footprint ""
		(layer "F.Cu")
		(at 34.417 -51.181 180)
		(property "Reference" "R316"
			(at 0 0 180)
			(layer "F.SilkS")
			(hide yes)
			(effects
				(font
					(size 1.27 1.27)
				)
			)
		)
		(property "Value" ""
			(at 0 0 180)
			(layer "F.Fab")
			(effects
				(font
					(size 1.27 1.27)
				)
			)
		)
		(duplicate_pad_numbers_are_jumpers no)
		(fp_line
			(start 0.7874 0.4064)
			(end -0.7874 0.4064)
			(stroke
				(width 0.1524)
				(type default)
			)
			(layer "F.SilkS")
		)
		(fp_line
			(start 0.7874 -0.4064)
			(end 0.7874 0.4064)
			(stroke
				(width 0.1524)
				(type default)
			)
			(layer "F.SilkS")
		)
		(fp_line
			(start -0.7874 0.4064)
			(end -0.7874 -0.4064)
			(stroke
				(width 0.1524)
				(type default)
			)
			(layer "F.SilkS")
		)
		(fp_line
			(start -0.7874 -0.4064)
			(end 0.7874 -0.4064)
			(stroke
				(width 0.1524)
				(type default)
			)
			(layer "F.SilkS")
		)
		(fp_line
			(start 0.67945 0.3048)
			(end 0.120396 0.3048)
			(stroke
				(width 0.1)
				(type default)
			)
			(layer "F.Fab")
		)
		(fp_line
			(start 0.67945 -0.3048)
			(end 0.67945 0.3048)
			(stroke
				(width 0.1)
				(type default)
			)
			(layer "F.Fab")
		)
		(fp_line
			(start 0.12065 -0.2794)
			(end 0.12065 -0.3048)
			(stroke
				(width 0.1)
				(type default)
			)
			(layer "F.Fab")
		)
		(fp_line
			(start 0.12065 -0.3048)
			(end 0.67945 -0.3048)
			(stroke
				(width 0.1)
				(type default)
			)
			(layer "F.Fab")
		)
		(fp_line
			(start 0.120396 0.3048)
			(end 0.120396 0.2794)
			(stroke
				(width 0.1)
				(type default)
			)
			(layer "F.Fab")
		)
		(fp_line
			(start 0.120396 0.2794)
			(end -0.12065 0.2794)
			(stroke
				(width 0.1)
				(type default)
			)
			(layer "F.Fab")
		)
		(fp_line
			(start -0.12065 0.3048)
			(end -0.67945 0.3048)
			(stroke
				(width 0.1)
				(type default)
			)
			(layer "F.Fab")
		)
		(fp_line
			(start -0.12065 0.2794)
			(end -0.12065 0.3048)
			(stroke
				(width 0.1)
				(type default)
			)
			(layer "F.Fab")
		)
		(fp_line
			(start -0.12065 -0.2794)
			(end 0.12065 -0.2794)
			(stroke
				(width 0.1)
				(type default)
			)
			(layer "F.Fab")
		)
		(fp_line
			(start -0.12065 -0.305054)
			(end -0.12065 -0.2794)
			(stroke
				(width 0.1)
				(type default)
			)
			(layer "F.Fab")
		)
		(fp_line
			(start -0.67945 0.3048)
			(end -0.67945 -0.305054)
			(stroke
				(width 0.1)
				(type default)
			)
			(layer "F.Fab")
		)
		(fp_line
			(start -0.67945 -0.305054)
			(end -0.12065 -0.305054)
			(stroke
				(width 0.1)
				(type default)
			)
			(layer "F.Fab")
		)
		(pad "1" smd circle
			(at -0.40005 0 180)
			(size 0 0)
			(layers "F.Cu" "F.Mask" "F.Paste")
			(net "BMC_PWR_LED")
		)
		(pad "2" smd circle
			(at 0.40005 0 180)
			(size 0 0)
			(layers "F.Cu" "F.Mask" "F.Paste")
			(net "PWR_LED")
		)
	)
	(footprint ""
		(layer "F.Cu")
		(at 84.0486 -81.0006 -90)
		(property "Reference" "C278"
			(at 0 0 270)
			(layer "F.SilkS")
			(hide yes)
			(effects
				(font
					(size 1.27 1.27)
				)
			)
		)
		(property "Value" ""
			(at 0 0 270)
			(layer "F.Fab")
			(effects
				(font
					(size 1.27 1.27)
				)
			)
		)
		(duplicate_pad_numbers_are_jumpers no)
		(fp_line
			(start -0.7874 0.4064)
			(end -0.7874 -0.4064)
			(stroke
				(width 0.1524)
				(type default)
			)
			(layer "F.SilkS")
		)
		(fp_line
			(start 0.7874 0.4064)
			(end -0.7874 0.4064)
			(stroke
				(width 0.1524)
				(type default)
			)
			(layer "F.SilkS")
		)
		(fp_line
			(start -0.7874 -0.4064)
			(end 0.7874 -0.4064)
			(stroke
				(width 0.1524)
				(type default)
			)
			(layer "F.SilkS")
		)
		(fp_line
			(start 0.7874 -0.4064)
			(end 0.7874 0.4064)
			(stroke
				(width 0.1524)
				(type default)
			)
			(layer "F.SilkS")
		)
		(fp_line
			(start -0.67945 0.3048)
			(end -0.67945 -0.305054)
			(stroke
				(width 0.1)
				(type default)
			)
			(layer "F.Fab")
		)
		(fp_line
			(start -0.12065 0.3048)
			(end -0.67945 0.3048)
			(stroke
				(width 0.1)
				(type default)
			)
			(layer "F.Fab")
		)
		(fp_line
			(start 0.120396 0.3048)
			(end 0.120396 0.2794)
			(stroke
				(width 0.1)
				(type default)
			)
			(layer "F.Fab")
		)
		(fp_line
			(start 0.67945 0.3048)
			(end 0.120396 0.3048)
			(stroke
				(width 0.1)
				(type default)
			)
			(layer "F.Fab")
		)
		(fp_line
			(start -0.12065 0.2794)
			(end -0.12065 0.3048)
			(stroke
				(width 0.1)
				(type default)
			)
			(layer "F.Fab")
		)
		(fp_line
			(start 0.120396 0.2794)
			(end -0.12065 0.2794)
			(stroke
				(width 0.1)
				(type default)
			)
			(layer "F.Fab")
		)
		(fp_line
			(start -0.12065 -0.2794)
			(end 0.12065 -0.2794)
			(stroke
				(width 0.1)
				(type default)
			)
			(layer "F.Fab")
		)
		(fp_line
			(start 0.12065 -0.2794)
			(end 0.12065 -0.3048)
			(stroke
				(width 0.1)
				(type default)
			)
			(layer "F.Fab")
		)
		(fp_line
			(start 0.12065 -0.3048)
			(end 0.67945 -0.3048)
			(stroke
				(width 0.1)
				(type default)
			)
			(layer "F.Fab")
		)
		(fp_line
			(start 0.67945 -0.3048)
			(end 0.67945 0.3048)
			(stroke
				(width 0.1)
				(type default)
			)
			(layer "F.Fab")
		)
		(fp_line
			(start -0.67945 -0.305054)
			(end -0.12065 -0.305054)
			(stroke
				(width 0.1)
				(type default)
			)
			(layer "F.Fab")
		)
		(fp_line
			(start -0.12065 -0.305054)
			(end -0.12065 -0.2794)
			(stroke
				(width 0.1)
				(type default)
			)
			(layer "F.Fab")
		)
		(pad "1" smd circle
			(at -0.40005 0 270)
			(size 0 0)
			(layers "F.Cu" "F.Mask" "F.Paste")
			(net "P12V_AUX")
		)
		(pad "2" smd circle
			(at 0.40005 0 270)
			(size 0 0)
			(layers "F.Cu" "F.Mask" "F.Paste")
			(net "GND")
		)
	)
	(footprint ""
		(layer "F.Cu")
		(at 7.999984 -2.94005)
		(property "Reference" "SW6"
			(at -1.015238 -5.161534 0)
			(unlocked yes)
			(layer "F.SilkS")
			(effects
				(font
					(size 0.7874 0.5842)
					(thickness 0.1524)
				)
				(justify left)
			)
		)
		(property "Value" ""
			(at 0 0 0)
			(layer "F.Fab")
			(effects
				(font
					(size 1.27 1.27)
				)
			)
		)
		(duplicate_pad_numbers_are_jumpers no)
		(fp_line
			(start -3.700018 -4.549902)
			(end -3.700018 -2.51206)
			(stroke
				(width 0.1524)
				(type default)
			)
			(layer "F.SilkS")
		)
		(fp_line
			(start -3.700018 -0.98806)
			(end -3.700018 -0.88646)
			(stroke
				(width 0.1524)
				(type default)
			)
			(layer "F.SilkS")
		)
		(fp_line
			(start -3.700018 1.39954)
			(end -3.700018 1.549908)
			(stroke
				(width 0.1524)
				(type default)
			)
			(layer "F.SilkS")
		)
		(fp_line
			(start -3.700018 1.549908)
			(end -1.75006 1.549908)
			(stroke
				(width 0.1524)
				(type default)
			)
			(layer "F.SilkS")
		)
		(fp_line
			(start -3.1496 -4.549902)
			(end -3.700018 -4.549902)
			(stroke
				(width 0.1524)
				(type default)
			)
			(layer "F.SilkS")
		)
		(fp_line
			(start -1.75006 1.549908)
			(end -1.75006 4.549902)
			(stroke
				(width 0.1524)
				(type default)
			)
			(layer "F.SilkS")
		)
		(fp_line
			(start -1.75006 4.549902)
			(end 1.75006 4.549902)
			(stroke
				(width 0.1524)
				(type default)
			)
			(layer "F.SilkS")
		)
		(fp_line
			(start 1.3716 -4.549902)
			(end -1.3716 -4.549902)
			(stroke
				(width 0.1524)
				(type default)
			)
			(layer "F.SilkS")
		)
		(fp_line
			(start 1.75006 1.549908)
			(end 3.700018 1.549908)
			(stroke
				(width 0.1524)
				(type default)
			)
			(layer "F.SilkS")
		)
		(fp_line
			(start 1.75006 4.549902)
			(end 1.75006 1.549908)
			(stroke
				(width 0.1524)
				(type default)
			)
			(layer "F.SilkS")
		)
		(fp_line
			(start 3.700018 -4.549902)
			(end 3.1496 -4.549902)
			(stroke
				(width 0.1524)
				(type default)
			)
			(layer "F.SilkS")
		)
		(fp_line
			(start 3.700018 -2.51206)
			(end 3.700018 -4.549902)
			(stroke
				(width 0.1524)
				(type default)
			)
			(layer "F.SilkS")
		)
		(fp_line
			(start 3.700018 -0.88646)
			(end 3.700018 -0.98806)
			(stroke
				(width 0.1524)
				(type default)
			)
			(layer "F.SilkS")
		)
		(fp_line
			(start 3.700018 1.549908)
			(end 3.700018 1.39954)
			(stroke
				(width 0.1524)
				(type default)
			)
			(layer "F.SilkS")
		)
		(fp_poly
			(pts
				(xy -3.883914 -4.043934) (xy -5.310886 -3.330448) (xy -5.310886 -4.75742)
			)
			(stroke
				(width 0)
				(type default)
			)
			(fill yes)
			(layer "F.SilkS")
		)
		(fp_line
			(start -3.700018 -4.549902)
			(end -3.700018 1.549908)
			(stroke
				(width 0.1)
				(type default)
			)
			(layer "F.Fab")
		)
		(fp_line
			(start -3.700018 1.549908)
			(end -1.75006 1.549908)
			(stroke
				(width 0.1)
				(type default)
			)
			(layer "F.Fab")
		)
		(fp_line
			(start -1.75006 1.549908)
			(end -1.75006 4.549902)
			(stroke
				(width 0.1)
				(type default)
			)
			(layer "F.Fab")
		)
		(fp_line
			(start -1.75006 4.549902)
			(end 1.75006 4.549902)
			(stroke
				(width 0.1)
				(type default)
			)
			(layer "F.Fab")
		)
		(fp_line
			(start 1.75006 1.549908)
			(end 3.700018 1.549908)
			(stroke
				(width 0.1)
				(type default)
			)
			(layer "F.Fab")
		)
		(fp_line
			(start 1.75006 4.549902)
			(end 1.75006 1.549908)
			(stroke
				(width 0.1)
				(type default)
			)
			(layer "F.Fab")
		)
		(fp_line
			(start 3.700018 -4.549902)
			(end -3.700018 -4.549902)
			(stroke
				(width 0.1)
				(type default)
			)
			(layer "F.Fab")
		)
		(fp_line
			(start 3.700018 1.549908)
			(end 3.700018 -4.549902)
			(stroke
				(width 0.1)
				(type default)
			)
			(layer "F.Fab")
		)
		(fp_poly
			(pts
				(xy -3.883914 -4.043934) (xy -5.310886 -3.330448) (xy -5.310886 -4.75742)
			)
			(stroke
				(width 0)
				(type default)
			)
			(fill yes)
			(layer "F.Fab")
		)
		(pad "" np_thru_hole circle
			(at -3.50012 -1.75006)
			(size 0.9144 0.9144)
			(drill 0.9144)
			(layers "*.Cu" "*.Mask")
			(clearance 0.381)
			(thermal_gap 0.381)
		)
		(pad "" np_thru_hole circle
			(at 3.50012 -1.75006)
			(size 0.9144 0.9144)
			(drill 0.9144)
			(layers "*.Cu" "*.Mask")
			(clearance 0.381)
			(thermal_gap 0.381)
		)
		(pad "1" smd rect
			(at -2.249932 -4.05003)
			(size 1.4986 2.0066)
			(layers "F.Cu" "F.Mask" "F.Paste")
			(net "GND")
		)
		(pad "2" smd rect
			(at 2.249932 -4.05003)
			(size 1.4986 2.0066)
			(layers "F.Cu" "F.Mask" "F.Paste")
			(net "REAR_PWR_BTN_N")
		)
		(pad "3" smd rect
			(at -4.19989 0.249936)
			(size 2.0066 2.0066)
			(layers "F.Cu" "F.Mask" "F.Paste")
			(net "GND")
		)
		(pad "4" smd rect
			(at 4.19989 0.249936)
			(size 2.0066 2.0066)
			(layers "F.Cu" "F.Mask" "F.Paste")
			(net "GND")
		)
		(zone
			(layers "F.Cu" "B.Cu" "In1.Cu" "In2.Cu" "In3.Cu" "In4.Cu" "In5.Cu" "In6.Cu"
				"In7.Cu" "In8.Cu" "In9.Cu" "In10.Cu"
			)
			(hatch none 0.5)
			(connect_pads
				(clearance 0)
			)
			(min_thickness 0.25)
			(keepout
				(tracks not_allowed)
				(vias allowed)
				(pads allowed)
				(copperpour not_allowed)
				(footprints allowed)
			)
			(placement
				(enabled no)
				(sheetname "")
			)
			(fill
				(thermal_gap 0.5)
				(thermal_bridge_width 0.5)
				(island_removal_mode 0)
			)
			(polygon
				(pts
					(arc
						(start 5.363718 -4.69011)
						(mid 3.63601 -4.69011)
						(end 5.363718 -4.69011)
					)
				)
			)
		)
		(zone
			(layers "F.Cu" "B.Cu" "In1.Cu" "In2.Cu" "In3.Cu" "In4.Cu" "In5.Cu" "In6.Cu"
				"In7.Cu" "In8.Cu" "In9.Cu" "In10.Cu"
			)
			(hatch none 0.5)
			(connect_pads
				(clearance 0)
			)
			(min_thickness 0.25)
			(keepout
				(tracks not_allowed)
				(vias allowed)
				(pads allowed)
				(copperpour not_allowed)
				(footprints allowed)
			)
			(placement
				(enabled no)
				(sheetname "")
			)
			(fill
				(thermal_gap 0.5)
				(thermal_bridge_width 0.5)
				(island_removal_mode 0)
			)
			(polygon
				(pts
					(arc
						(start 12.363704 -4.69011)
						(mid 10.636504 -4.69011)
						(end 12.363704 -4.69011)
					)
				)
			)
		)
	)
	(footprint ""
		(layer "F.Cu")
		(at 23.749 -66.167 90)
		(property "Reference" "C19"
			(at 0 0 90)
			(layer "F.SilkS")
			(hide yes)
			(effects
				(font
					(size 1.27 1.27)
				)
			)
		)
		(property "Value" ""
			(at 0 0 90)
			(layer "F.Fab")
			(effects
				(font
					(size 1.27 1.27)
				)
			)
		)
		(duplicate_pad_numbers_are_jumpers no)
		(fp_line
			(start 0.7874 -0.4064)
			(end 0.7874 0.4064)
			(stroke
				(width 0.1524)
				(type default)
			)
			(layer "F.SilkS")
		)
		(fp_line
			(start -0.7874 -0.4064)
			(end 0.7874 -0.4064)
			(stroke
				(width 0.1524)
				(type default)
			)
			(layer "F.SilkS")
		)
		(fp_line
			(start 0.7874 0.4064)
			(end -0.7874 0.4064)
			(stroke
				(width 0.1524)
				(type default)
			)
			(layer "F.SilkS")
		)
		(fp_line
			(start -0.7874 0.4064)
			(end -0.7874 -0.4064)
			(stroke
				(width 0.1524)
				(type default)
			)
			(layer "F.SilkS")
		)
		(fp_line
			(start -0.12065 -0.305054)
			(end -0.12065 -0.2794)
			(stroke
				(width 0.1)
				(type default)
			)
			(layer "F.Fab")
		)
		(fp_line
			(start -0.67945 -0.305054)
			(end -0.12065 -0.305054)
			(stroke
				(width 0.1)
				(type default)
			)
			(layer "F.Fab")
		)
		(fp_line
			(start 0.67945 -0.3048)
			(end 0.67945 0.3048)
			(stroke
				(width 0.1)
				(type default)
			)
			(layer "F.Fab")
		)
		(fp_line
			(start 0.12065 -0.3048)
			(end 0.67945 -0.3048)
			(stroke
				(width 0.1)
				(type default)
			)
			(layer "F.Fab")
		)
		(fp_line
			(start 0.12065 -0.2794)
			(end 0.12065 -0.3048)
			(stroke
				(width 0.1)
				(type default)
			)
			(layer "F.Fab")
		)
		(fp_line
			(start -0.12065 -0.2794)
			(end 0.12065 -0.2794)
			(stroke
				(width 0.1)
				(type default)
			)
			(layer "F.Fab")
		)
		(fp_line
			(start 0.120396 0.2794)
			(end -0.12065 0.2794)
			(stroke
				(width 0.1)
				(type default)
			)
			(layer "F.Fab")
		)
		(fp_line
			(start -0.12065 0.2794)
			(end -0.12065 0.3048)
			(stroke
				(width 0.1)
				(type default)
			)
			(layer "F.Fab")
		)
		(fp_line
			(start 0.67945 0.3048)
			(end 0.120396 0.3048)
			(stroke
				(width 0.1)
				(type default)
			)
			(layer "F.Fab")
		)
		(fp_line
			(start 0.120396 0.3048)
			(end 0.120396 0.2794)
			(stroke
				(width 0.1)
				(type default)
			)
			(layer "F.Fab")
		)
		(fp_line
			(start -0.12065 0.3048)
			(end -0.67945 0.3048)
			(stroke
				(width 0.1)
				(type default)
			)
			(layer "F.Fab")
		)
		(fp_line
			(start -0.67945 0.3048)
			(end -0.67945 -0.305054)
			(stroke
				(width 0.1)
				(type default)
			)
			(layer "F.Fab")
		)
		(pad "1" smd circle
			(at -0.40005 0 90)
			(size 0 0)
			(layers "F.Cu" "F.Mask" "F.Paste")
			(net "P3V3_AUX")
		)
		(pad "2" smd circle
			(at 0.40005 0 90)
			(size 0 0)
			(layers "F.Cu" "F.Mask" "F.Paste")
			(net "GND")
		)
	)
)
